(kicad_pcb
	(version 20260206)
	(generator "pcbnew")
	(generator_version "10.0")
	(general
		(thickness 1.6)
		(legacy_teardrops no)
	)
	(paper "A4")
	(title_block
		(title "15969-1a.1015WZS0858.brd")
		(comment 1 "Tioga Pass / footprints 240-245 of 295")
	)
	(layers
		(0 "F.Cu" signal "TOP")
		(4 "In1.Cu" signal "L2GND")
		(6 "In2.Cu" signal "L3")
		(8 "In3.Cu" signal "L4")
		(10 "In4.Cu" signal "L5GND")
		(2 "B.Cu" signal "BOTTOM")
		(9 "F.Adhes" user "F.Adhesive")
		(11 "B.Adhes" user "B.Adhesive")
		(13 "F.Paste" user "Package Geometry/Pastemask Top")
		(15 "B.Paste" user "Package Geometry/Pastemask Bottom")
		(5 "F.SilkS" user "Ref Des/Silkscreen Top")
		(7 "B.SilkS" user "Ref Des/Silkscreen Bottom")
		(1 "F.Mask" user "Board Geometry/Soldermask Top")
		(3 "B.Mask" user "Board Geometry/Soldermask Bottom")
		(17 "Dwgs.User" user "User.Drawings")
		(19 "Cmts.User" user "User.Comments")
		(21 "Eco1.User" user "User.Eco1")
		(23 "Eco2.User" user "User.Eco2")
		(25 "Edge.Cuts" user "Board Geometry/Outline")
		(27 "Margin" user)
		(31 "F.CrtYd" user "Package Geometry/Place Bound Top")
		(29 "B.CrtYd" user "Package Geometry/Place Bound Bottom")
		(35 "F.Fab" user "Ref Des/Assembly Top")
		(33 "B.Fab" user "Ref Des/Assembly Bottom")
	)
	(footprint ""
		(layer "B.Cu")
		(at 42.7482 -1.5367 180)
		(property "Reference" "R27"
			(at 0 0 0)
			(layer "B.SilkS")
			(hide yes)
			(effects
				(font
					(size 1.27 1.27)
				)
				(justify mirror)
			)
		)
		(property "Value" "0R2F-1-GP"
			(at -0.064008 -3.993896 180)
			(unlocked yes)
			(layer "B.Fab")
			(hide yes)
			(effects
				(font
					(size 1.016 1.016)
					(thickness 0.1524)
				)
				(justify mirror)
			)
		)
		(property "Device Type" "R402H16"
			(at -0.064008 -5.517896 180)
			(unlocked yes)
			(layer "B.Fab")
			(hide yes)
			(effects
				(font
					(size 1.016 1.016)
					(thickness 0.1524)
				)
				(justify mirror)
			)
		)
		(duplicate_pad_numbers_are_jumpers no)
		(fp_line
			(start 0.508 -0.9398)
			(end 0.508 0.9398)
			(stroke
				(width 0.1524)
				(type default)
			)
			(layer "B.SilkS")
		)
		(fp_line
			(start -0.508 -0.9398)
			(end 0.508 -0.9398)
			(stroke
				(width 0.1524)
				(type default)
			)
			(layer "B.SilkS")
		)
		(fp_rect
			(start 0.508 0.9398)
			(end -0.508 -0.9398)
			(stroke
				(width 0)
				(type default)
			)
			(fill no)
			(layer "B.CrtYd")
		)
		(fp_rect
			(start 0.508 0.9398)
			(end -0.508 -0.9398)
			(stroke
				(width 0)
				(type default)
			)
			(fill no)
			(layer "B.Fab")
		)
		(pad "1" smd custom
			(at 0 -0.4445)
			(size 0.1397 0.1397)
			(layers "B.Cu" "B.Mask" "B.Paste")
			(net "SMCLK_BMC_SLOT2")
			(options
				(clearance outline)
				(anchor circle)
			)
			(primitives
				(gr_poly
					(pts
						(arc
							(start -0.1778 0.2794)
							(mid -0.249642 0.249642)
							(end -0.2794 0.1778)
						)
						(arc
							(start -0.2794 -0.1778)
							(mid -0.249642 -0.249642)
							(end -0.1778 -0.2794)
						)
						(arc
							(start 0.1778 -0.2794)
							(mid 0.249642 -0.249642)
							(end 0.2794 -0.1778)
						)
						(arc
							(start 0.2794 0.1778)
							(mid 0.249642 0.249642)
							(end 0.1778 0.2794)
						)
					)
					(width 0)
					(fill yes)
				)
			)
		)
		(pad "2" smd custom
			(at 0 0.4445)
			(size 0.1397 0.1397)
			(layers "B.Cu" "B.Mask" "B.Paste")
			(net "SMCLK_BMC_SLOT2_R")
			(options
				(clearance outline)
				(anchor circle)
			)
			(primitives
				(gr_poly
					(pts
						(arc
							(start -0.1778 0.2794)
							(mid -0.249642 0.249642)
							(end -0.2794 0.1778)
						)
						(arc
							(start -0.2794 -0.1778)
							(mid -0.249642 -0.249642)
							(end -0.1778 -0.2794)
						)
						(arc
							(start 0.1778 -0.2794)
							(mid 0.249642 -0.249642)
							(end 0.2794 -0.1778)
						)
						(arc
							(start 0.2794 0.1778)
							(mid 0.249642 0.249642)
							(end 0.1778 0.2794)
						)
					)
					(width 0)
					(fill yes)
				)
			)
		)
	)
	(footprint ""
		(layer "B.Cu")
		(at 44.4119 -2.3622 -90)
		(property "Reference" "R32"
			(at 0 0 90)
			(layer "B.SilkS")
			(hide yes)
			(effects
				(font
					(size 1.27 1.27)
				)
				(justify mirror)
			)
		)
		(property "Value" "0R2F-1-GP"
			(at -0.064008 -3.993896 270)
			(unlocked yes)
			(layer "B.Fab")
			(hide yes)
			(effects
				(font
					(size 1.016 1.016)
					(thickness 0.1524)
				)
				(justify mirror)
			)
		)
		(property "Device Type" "R402H16"
			(at -0.064008 -5.517896 270)
			(unlocked yes)
			(layer "B.Fab")
			(hide yes)
			(effects
				(font
					(size 1.016 1.016)
					(thickness 0.1524)
				)
				(justify mirror)
			)
		)
		(duplicate_pad_numbers_are_jumpers no)
		(fp_line
			(start -0.508 -0.9398)
			(end 0.508 -0.9398)
			(stroke
				(width 0.1524)
				(type default)
			)
			(layer "B.SilkS")
		)
		(fp_line
			(start 0.508 -0.9398)
			(end 0.508 0.9398)
			(stroke
				(width 0.1524)
				(type default)
			)
			(layer "B.SilkS")
		)
		(fp_rect
			(start 0.508 0.9398)
			(end -0.508 -0.9398)
			(stroke
				(width 0)
				(type default)
			)
			(fill no)
			(layer "B.CrtYd")
		)
		(fp_rect
			(start 0.508 0.9398)
			(end -0.508 -0.9398)
			(stroke
				(width 0)
				(type default)
			)
			(fill no)
			(layer "B.Fab")
		)
		(pad "1" smd custom
			(at 0 -0.4445 90)
			(size 0.1397 0.1397)
			(layers "B.Cu" "B.Mask" "B.Paste")
			(net "SMDAT_PCH_SLOT2")
			(options
				(clearance outline)
				(anchor circle)
			)
			(primitives
				(gr_poly
					(pts
						(arc
							(start -0.1778 0.2794)
							(mid -0.249642 0.249642)
							(end -0.2794 0.1778)
						)
						(arc
							(start -0.2794 -0.1778)
							(mid -0.249642 -0.249642)
							(end -0.1778 -0.2794)
						)
						(arc
							(start 0.1778 -0.2794)
							(mid 0.249642 -0.249642)
							(end 0.2794 -0.1778)
						)
						(arc
							(start 0.2794 0.1778)
							(mid 0.249642 0.249642)
							(end 0.1778 0.2794)
						)
					)
					(width 0)
					(fill yes)
				)
			)
		)
		(pad "2" smd custom
			(at 0 0.4445 90)
			(size 0.1397 0.1397)
			(layers "B.Cu" "B.Mask" "B.Paste")
			(net "SMDAT_PCH_SLOT2_R")
			(options
				(clearance outline)
				(anchor circle)
			)
			(primitives
				(gr_poly
					(pts
						(arc
							(start -0.1778 0.2794)
							(mid -0.249642 0.249642)
							(end -0.2794 0.1778)
						)
						(arc
							(start -0.2794 -0.1778)
							(mid -0.249642 -0.249642)
							(end -0.1778 -0.2794)
						)
						(arc
							(start 0.1778 -0.2794)
							(mid 0.249642 -0.249642)
							(end 0.2794 -0.1778)
						)
						(arc
							(start 0.2794 0.1778)
							(mid 0.249642 0.249642)
							(end 0.1778 0.2794)
						)
					)
					(width 0)
					(fill yes)
				)
			)
		)
	)
	(footprint ""
		(layer "B.Cu")
		(at 123.4186 -30.7594)
		(property "Reference" "CU2"
			(at 0 0 0)
			(layer "B.SilkS")
			(hide yes)
			(effects
				(font
					(size 1.27 1.27)
				)
				(justify mirror)
			)
		)
		(property "Value" "SC1U6D3V3KX-2GP"
			(at 0 -2.8194 0)
			(unlocked yes)
			(layer "B.Fab")
			(hide yes)
			(effects
				(font
					(size 1.016 1.016)
					(thickness 0.1524)
				)
				(justify mirror)
			)
		)
		(property "Device Type" "C603H36"
			(at 0 -4.3434 0)
			(unlocked yes)
			(layer "B.Fab")
			(hide yes)
			(effects
				(font
					(size 1.016 1.016)
					(thickness 0.1524)
				)
				(justify mirror)
			)
		)
		(duplicate_pad_numbers_are_jumpers no)
		(fp_line
			(start -0.508 0)
			(end 0.508 0)
			(stroke
				(width 0.2032)
				(type default)
			)
			(layer "B.SilkS")
		)
		(fp_rect
			(start 0.5842 1.3335)
			(end -0.5842 -1.3335)
			(stroke
				(width 0)
				(type default)
			)
			(fill no)
			(layer "B.CrtYd")
		)
		(fp_rect
			(start 0.5842 1.3335)
			(end -0.5842 -1.3335)
			(stroke
				(width 0)
				(type default)
			)
			(fill no)
			(layer "B.Fab")
		)
		(pad "1" smd custom
			(at 0 -0.762 180)
			(size 0.2159 0.2159)
			(layers "B.Cu" "B.Mask" "B.Paste")
			(net "P3V3_USB_HUB")
			(options
				(clearance outline)
				(anchor circle)
			)
			(primitives
				(gr_poly
					(pts
						(arc
							(start -0.3302 0.4318)
							(mid -0.402042 0.402042)
							(end -0.4318 0.3302)
						)
						(arc
							(start -0.4318 -0.3302)
							(mid -0.402042 -0.402042)
							(end -0.3302 -0.4318)
						)
						(arc
							(start 0.3302 -0.4318)
							(mid 0.402042 -0.402042)
							(end 0.4318 -0.3302)
						)
						(arc
							(start 0.4318 0.3302)
							(mid 0.402042 0.402042)
							(end 0.3302 0.4318)
						)
					)
					(width 0)
					(fill yes)
				)
			)
		)
		(pad "2" smd custom
			(at 0 0.762 180)
			(size 0.2159 0.2159)
			(layers "B.Cu" "B.Mask" "B.Paste")
			(net "GND")
			(options
				(clearance outline)
				(anchor circle)
			)
			(primitives
				(gr_poly
					(pts
						(arc
							(start -0.3302 0.4318)
							(mid -0.402042 0.402042)
							(end -0.4318 0.3302)
						)
						(arc
							(start -0.4318 -0.3302)
							(mid -0.402042 -0.402042)
							(end -0.3302 -0.4318)
						)
						(arc
							(start 0.3302 -0.4318)
							(mid 0.402042 -0.402042)
							(end 0.4318 -0.3302)
						)
						(arc
							(start 0.4318 0.3302)
							(mid 0.402042 0.402042)
							(end 0.3302 0.4318)
						)
					)
					(width 0)
					(fill yes)
				)
			)
		)
	)
	(footprint ""
		(layer "B.Cu")
		(at 16.256 -7.4803 -90)
		(property "Reference" "PR7"
			(at 0 0 90)
			(layer "B.SilkS")
			(hide yes)
			(effects
				(font
					(size 1.27 1.27)
				)
				(justify mirror)
			)
		)
		(property "Value" "8K87R2F-2-GP"
			(at -0.064008 -3.993896 270)
			(unlocked yes)
			(layer "B.Fab")
			(hide yes)
			(effects
				(font
					(size 1.016 1.016)
					(thickness 0.1524)
				)
				(justify mirror)
			)
		)
		(property "Device Type" "R402H16"
			(at -0.064008 -5.517896 270)
			(unlocked yes)
			(layer "B.Fab")
			(hide yes)
			(effects
				(font
					(size 1.016 1.016)
					(thickness 0.1524)
				)
				(justify mirror)
			)
		)
		(duplicate_pad_numbers_are_jumpers no)
		(fp_line
			(start -0.508 -0.9398)
			(end 0.508 -0.9398)
			(stroke
				(width 0.1524)
				(type default)
			)
			(layer "B.SilkS")
		)
		(fp_line
			(start 0.508 -0.9398)
			(end 0.508 0.9398)
			(stroke
				(width 0.1524)
				(type default)
			)
			(layer "B.SilkS")
		)
		(fp_rect
			(start 0.508 0.9398)
			(end -0.508 -0.9398)
			(stroke
				(width 0)
				(type default)
			)
			(fill no)
			(layer "B.CrtYd")
		)
		(fp_rect
			(start 0.508 0.9398)
			(end -0.508 -0.9398)
			(stroke
				(width 0)
				(type default)
			)
			(fill no)
			(layer "B.Fab")
		)
		(pad "1" smd custom
			(at 0 -0.4445 90)
			(size 0.1397 0.1397)
			(layers "B.Cu" "B.Mask" "B.Paste")
			(net "P3V3_CS")
			(options
				(clearance outline)
				(anchor circle)
			)
			(primitives
				(gr_poly
					(pts
						(arc
							(start -0.1778 0.2794)
							(mid -0.249642 0.249642)
							(end -0.2794 0.1778)
						)
						(arc
							(start -0.2794 -0.1778)
							(mid -0.249642 -0.249642)
							(end -0.1778 -0.2794)
						)
						(arc
							(start 0.1778 -0.2794)
							(mid 0.249642 -0.249642)
							(end 0.2794 -0.1778)
						)
						(arc
							(start 0.2794 0.1778)
							(mid 0.249642 0.249642)
							(end 0.1778 0.2794)
						)
					)
					(width 0)
					(fill yes)
				)
			)
		)
		(pad "2" smd custom
			(at 0 0.4445 90)
			(size 0.1397 0.1397)
			(layers "B.Cu" "B.Mask" "B.Paste")
			(net "AGND_P3V3")
			(options
				(clearance outline)
				(anchor circle)
			)
			(primitives
				(gr_poly
					(pts
						(arc
							(start -0.1778 0.2794)
							(mid -0.249642 0.249642)
							(end -0.2794 0.1778)
						)
						(arc
							(start -0.2794 -0.1778)
							(mid -0.249642 -0.249642)
							(end -0.1778 -0.2794)
						)
						(arc
							(start 0.1778 -0.2794)
							(mid 0.249642 -0.249642)
							(end 0.2794 -0.1778)
						)
						(arc
							(start 0.2794 0.1778)
							(mid 0.249642 0.249642)
							(end 0.1778 0.2794)
						)
					)
					(width 0)
					(fill yes)
				)
			)
		)
	)
	(footprint ""
		(layer "B.Cu")
		(at 129.3749 0.3302 180)
		(property "Reference" "R24"
			(at 0 0 0)
			(layer "B.SilkS")
			(hide yes)
			(effects
				(font
					(size 1.27 1.27)
				)
				(justify mirror)
			)
		)
		(property "Value" "4K7R2F-GP"
			(at -0.064008 -3.993896 180)
			(unlocked yes)
			(layer "B.Fab")
			(hide yes)
			(effects
				(font
					(size 1.016 1.016)
					(thickness 0.1524)
				)
				(justify mirror)
			)
		)
		(property "Device Type" "R402H16"
			(at -0.064008 -5.517896 180)
			(unlocked yes)
			(layer "B.Fab")
			(hide yes)
			(effects
				(font
					(size 1.016 1.016)
					(thickness 0.1524)
				)
				(justify mirror)
			)
		)
		(duplicate_pad_numbers_are_jumpers no)
		(fp_line
			(start 0.508 -0.9398)
			(end 0.508 0.9398)
			(stroke
				(width 0.1524)
				(type default)
			)
			(layer "B.SilkS")
		)
		(fp_line
			(start -0.508 -0.9398)
			(end 0.508 -0.9398)
			(stroke
				(width 0.1524)
				(type default)
			)
			(layer "B.SilkS")
		)
		(fp_rect
			(start 0.508 0.9398)
			(end -0.508 -0.9398)
			(stroke
				(width 0)
				(type default)
			)
			(fill no)
			(layer "B.CrtYd")
		)
		(fp_rect
			(start 0.508 0.9398)
			(end -0.508 -0.9398)
			(stroke
				(width 0)
				(type default)
			)
			(fill no)
			(layer "B.Fab")
		)
		(pad "1" smd custom
			(at 0 -0.4445)
			(size 0.1397 0.1397)
			(layers "B.Cu" "B.Mask" "B.Paste")
			(net "P3V3_STBY")
			(options
				(clearance outline)
				(anchor circle)
			)
			(primitives
				(gr_poly
					(pts
						(arc
							(start -0.1778 0.2794)
							(mid -0.249642 0.249642)
							(end -0.2794 0.1778)
						)
						(arc
							(start -0.2794 -0.1778)
							(mid -0.249642 -0.249642)
							(end -0.1778 -0.2794)
						)
						(arc
							(start 0.1778 -0.2794)
							(mid 0.249642 -0.249642)
							(end 0.2794 -0.1778)
						)
						(arc
							(start 0.2794 0.1778)
							(mid 0.249642 0.249642)
							(end 0.1778 0.2794)
						)
					)
					(width 0)
					(fill yes)
				)
			)
		)
		(pad "2" smd custom
			(at 0 0.4445)
			(size 0.1397 0.1397)
			(layers "B.Cu" "B.Mask" "B.Paste")
			(net "PU_P_MUX_SDA2")
			(options
				(clearance outline)
				(anchor circle)
			)
			(primitives
				(gr_poly
					(pts
						(arc
							(start -0.1778 0.2794)
							(mid -0.249642 0.249642)
							(end -0.2794 0.1778)
						)
						(arc
							(start -0.2794 -0.1778)
							(mid -0.249642 -0.249642)
							(end -0.1778 -0.2794)
						)
						(arc
							(start 0.1778 -0.2794)
							(mid 0.249642 -0.249642)
							(end 0.2794 -0.1778)
						)
						(arc
							(start 0.2794 0.1778)
							(mid 0.249642 0.249642)
							(end 0.1778 0.2794)
						)
					)
					(width 0)
					(fill yes)
				)
			)
		)
	)
	(footprint ""
		(layer "B.Cu")
		(at 102.2604 1.0668)
		(property "Reference" "R3"
			(at 0 0 0)
			(layer "B.SilkS")
			(hide yes)
			(effects
				(font
					(size 1.27 1.27)
				)
				(justify mirror)
			)
		)
		(property "Value" "4K7R2F-GP"
			(at -0.064008 -3.993896 0)
			(unlocked yes)
			(layer "B.Fab")
			(hide yes)
			(effects
				(font
					(size 1.016 1.016)
					(thickness 0.1524)
				)
				(justify mirror)
			)
		)
		(property "Device Type" "R402H16"
			(at -0.064008 -5.517896 0)
			(unlocked yes)
			(layer "B.Fab")
			(hide yes)
			(effects
				(font
					(size 1.016 1.016)
					(thickness 0.1524)
				)
				(justify mirror)
			)
		)
		(duplicate_pad_numbers_are_jumpers no)
		(fp_line
			(start -0.508 -0.9398)
			(end 0.508 -0.9398)
			(stroke
				(width 0.1524)
				(type default)
			)
			(layer "B.SilkS")
		)
		(fp_line
			(start 0.508 -0.9398)
			(end 0.508 0.9398)
			(stroke
				(width 0.1524)
				(type default)
			)
			(layer "B.SilkS")
		)
		(fp_rect
			(start 0.508 0.9398)
			(end -0.508 -0.9398)
			(stroke
				(width 0)
				(type default)
			)
			(fill no)
			(layer "B.CrtYd")
		)
		(fp_rect
			(start 0.508 0.9398)
			(end -0.508 -0.9398)
			(stroke
				(width 0)
				(type default)
			)
			(fill no)
			(layer "B.Fab")
		)
		(pad "1" smd custom
			(at 0 -0.4445 180)
			(size 0.1397 0.1397)
			(layers "B.Cu" "B.Mask" "B.Paste")
			(net "P3V3_STBY")
			(options
				(clearance outline)
				(anchor circle)
			)
			(primitives
				(gr_poly
					(pts
						(arc
							(start -0.1778 0.2794)
							(mid -0.249642 0.249642)
							(end -0.2794 0.1778)
						)
						(arc
							(start -0.2794 -0.1778)
							(mid -0.249642 -0.249642)
							(end -0.1778 -0.2794)
						)
						(arc
							(start 0.1778 -0.2794)
							(mid 0.249642 -0.249642)
							(end 0.2794 -0.1778)
						)
						(arc
							(start 0.2794 0.1778)
							(mid 0.249642 0.249642)
							(end 0.1778 0.2794)
						)
					)
					(width 0)
					(fill yes)
				)
			)
		)
		(pad "2" smd custom
			(at 0 0.4445 180)
			(size 0.1397 0.1397)
			(layers "B.Cu" "B.Mask" "B.Paste")
			(net "SMCLK_BMC_SLOT2")
			(options
				(clearance outline)
				(anchor circle)
			)
			(primitives
				(gr_poly
					(pts
						(arc
							(start -0.1778 0.2794)
							(mid -0.249642 0.249642)
							(end -0.2794 0.1778)
						)
						(arc
							(start -0.2794 -0.1778)
							(mid -0.249642 -0.249642)
							(end -0.1778 -0.2794)
						)
						(arc
							(start 0.1778 -0.2794)
							(mid 0.249642 -0.249642)
							(end 0.2794 -0.1778)
						)
						(arc
							(start 0.2794 0.1778)
							(mid 0.249642 0.249642)
							(end 0.1778 0.2794)
						)
					)
					(width 0)
					(fill yes)
				)
			)
		)
	)
)
